(kicad_pcb
	(version 20260206)
	(generator "pcbnew")
	(generator_version "10.0")
	(general
		(thickness 1.6)
		(legacy_teardrops no)
	)
	(paper "A4")
	(title_block
		(title "04192023_DAF0TMB3IC0_F0TG_MB_C_brd_V02_OCP.brd")
		(comment 1 "Grand Teton / footprints 2294-2298 of 8354")
	)
	(layers
		(0 "F.Cu" signal "TOP")
		(4 "In1.Cu" signal "GND")
		(6 "In2.Cu" signal "IN1")
		(8 "In3.Cu" signal "GND1")
		(10 "In4.Cu" signal "IN2")
		(12 "In5.Cu" signal "GND2")
		(14 "In6.Cu" signal "IN3")
		(16 "In7.Cu" signal "GND3")
		(18 "In8.Cu" signal "VCC")
		(20 "In9.Cu" signal "VCC1")
		(22 "In10.Cu" signal "GND4")
		(24 "In11.Cu" signal "IN4")
		(26 "In12.Cu" signal "GND5")
		(28 "In13.Cu" signal "IN5")
		(30 "In14.Cu" signal "GND6")
		(32 "In15.Cu" signal "IN6")
		(34 "In16.Cu" signal "GND7")
		(2 "B.Cu" signal "BOTTOM")
		(9 "F.Adhes" user "F.Adhesive")
		(11 "B.Adhes" user "B.Adhesive")
		(13 "F.Paste" user "Package Geometry/Pastemask Top")
		(15 "B.Paste" user "Package Geometry/Pastemask Bottom")
		(5 "F.SilkS" user "Ref Des/Silkscreen Top")
		(7 "B.SilkS" user "Ref Des/Silkscreen Bottom")
		(1 "F.Mask" user "Board Geometry/Soldermask Top")
		(3 "B.Mask" user "Board Geometry/Soldermask Bottom")
		(17 "Dwgs.User" user "User.Drawings")
		(19 "Cmts.User" user "User.Comments")
		(21 "Eco1.User" user "User.Eco1")
		(23 "Eco2.User" user "User.Eco2")
		(25 "Edge.Cuts" user "Board Geometry/Outline")
		(27 "Margin" user)
		(31 "F.CrtYd" user "Package Geometry/Place Bound Top")
		(29 "B.CrtYd" user "Package Geometry/Place Bound Bottom")
		(35 "F.Fab" user "Ref Des/Assembly Top")
		(33 "B.Fab" user "Ref Des/Assembly Bottom")
	)
	(footprint ""
		(layer "F.Cu")
		(at 22.07768 -432.437794)
		(property "Reference" "R3523"
			(at 0 0 0)
			(layer "F.SilkS")
			(hide yes)
			(effects
				(font
					(size 1.27 1.27)
				)
			)
		)
		(property "Value" ""
			(at 0 0 0)
			(layer "F.Fab")
			(effects
				(font
					(size 1.27 1.27)
				)
			)
		)
		(duplicate_pad_numbers_are_jumpers no)
		(fp_line
			(start -0.7874 -0.4064)
			(end 0.7874 -0.4064)
			(stroke
				(width 0.1524)
				(type default)
			)
			(layer "F.SilkS")
		)
		(fp_line
			(start -0.7874 0.4064)
			(end -0.7874 -0.4064)
			(stroke
				(width 0.1524)
				(type default)
			)
			(layer "F.SilkS")
		)
		(fp_line
			(start 0.7874 -0.4064)
			(end 0.7874 0.4064)
			(stroke
				(width 0.1524)
				(type default)
			)
			(layer "F.SilkS")
		)
		(fp_line
			(start 0.7874 0.4064)
			(end -0.7874 0.4064)
			(stroke
				(width 0.1524)
				(type default)
			)
			(layer "F.SilkS")
		)
		(fp_line
			(start -0.67945 -0.305054)
			(end -0.12065 -0.305054)
			(stroke
				(width 0.1)
				(type default)
			)
			(layer "F.Fab")
		)
		(fp_line
			(start -0.67945 0.3048)
			(end -0.67945 -0.305054)
			(stroke
				(width 0.1)
				(type default)
			)
			(layer "F.Fab")
		)
		(fp_line
			(start -0.12065 -0.305054)
			(end -0.12065 -0.2794)
			(stroke
				(width 0.1)
				(type default)
			)
			(layer "F.Fab")
		)
		(fp_line
			(start -0.12065 -0.2794)
			(end 0.12065 -0.2794)
			(stroke
				(width 0.1)
				(type default)
			)
			(layer "F.Fab")
		)
		(fp_line
			(start -0.12065 0.2794)
			(end -0.12065 0.3048)
			(stroke
				(width 0.1)
				(type default)
			)
			(layer "F.Fab")
		)
		(fp_line
			(start -0.12065 0.3048)
			(end -0.67945 0.3048)
			(stroke
				(width 0.1)
				(type default)
			)
			(layer "F.Fab")
		)
		(fp_line
			(start 0.120396 0.2794)
			(end -0.12065 0.2794)
			(stroke
				(width 0.1)
				(type default)
			)
			(layer "F.Fab")
		)
		(fp_line
			(start 0.120396 0.3048)
			(end 0.120396 0.2794)
			(stroke
				(width 0.1)
				(type default)
			)
			(layer "F.Fab")
		)
		(fp_line
			(start 0.12065 -0.3048)
			(end 0.67945 -0.3048)
			(stroke
				(width 0.1)
				(type default)
			)
			(layer "F.Fab")
		)
		(fp_line
			(start 0.12065 -0.2794)
			(end 0.12065 -0.3048)
			(stroke
				(width 0.1)
				(type default)
			)
			(layer "F.Fab")
		)
		(fp_line
			(start 0.67945 -0.3048)
			(end 0.67945 0.3048)
			(stroke
				(width 0.1)
				(type default)
			)
			(layer "F.Fab")
		)
		(fp_line
			(start 0.67945 0.3048)
			(end 0.120396 0.3048)
			(stroke
				(width 0.1)
				(type default)
			)
			(layer "F.Fab")
		)
		(pad "1" smd circle
			(at -0.40005 0)
			(size 0 0)
			(layers "F.Cu" "F.Mask" "F.Paste")
			(net "P3V3_AUX")
		)
		(pad "2" smd circle
			(at 0.40005 0)
			(size 0 0)
			(layers "F.Cu" "F.Mask" "F.Paste")
			(net "SMB_1_BMC_GPU_BUF_R_SCL")
		)
	)
	(footprint ""
		(layer "F.Cu")
		(at 160.057338 -20.068794 -90)
		(property "Reference" "C2077"
			(at 0 0 270)
			(layer "F.SilkS")
			(hide yes)
			(effects
				(font
					(size 1.27 1.27)
				)
			)
		)
		(property "Value" ""
			(at 0 0 270)
			(layer "F.Fab")
			(effects
				(font
					(size 1.27 1.27)
				)
			)
		)
		(duplicate_pad_numbers_are_jumpers no)
		(fp_line
			(start -0.299974 0.150114)
			(end -0.299974 -0.150114)
			(stroke
				(width 0.1)
				(type default)
			)
			(layer "F.Fab")
		)
		(fp_line
			(start 0.299974 0.150114)
			(end -0.299974 0.150114)
			(stroke
				(width 0.1)
				(type default)
			)
			(layer "F.Fab")
		)
		(fp_line
			(start -0.299974 -0.150114)
			(end 0.299974 -0.150114)
			(stroke
				(width 0.1)
				(type default)
			)
			(layer "F.Fab")
		)
		(fp_line
			(start 0.299974 -0.150114)
			(end 0.299974 0.150114)
			(stroke
				(width 0.1)
				(type default)
			)
			(layer "F.Fab")
		)
		(pad "1" smd rect
			(at -0.2667 0 270)
			(size 0.3048 0.381)
			(layers "F.Cu" "F.Mask" "F.Paste")
			(net "P2E_CPU0_P5_TX_DP")
		)
		(pad "2" smd rect
			(at 0.2667 0 270)
			(size 0.3048 0.381)
			(layers "F.Cu" "F.Mask" "F.Paste")
			(net "P2E_CPU0_P5_TX_C_DP")
		)
	)
	(footprint ""
		(layer "F.Cu")
		(at 69.33057 -168.93032 90)
		(property "Reference" "PC126_C0P1_6"
			(at 0 0 90)
			(layer "F.SilkS")
			(hide yes)
			(effects
				(font
					(size 1.27 1.27)
				)
			)
		)
		(property "Value" ""
			(at 0 0 90)
			(layer "F.Fab")
			(effects
				(font
					(size 1.27 1.27)
				)
			)
		)
		(duplicate_pad_numbers_are_jumpers no)
		(fp_line
			(start 0.7874 -0.4064)
			(end 0.7874 0.4064)
			(stroke
				(width 0.1524)
				(type default)
			)
			(layer "F.SilkS")
		)
		(fp_line
			(start -0.7874 -0.4064)
			(end 0.7874 -0.4064)
			(stroke
				(width 0.1524)
				(type default)
			)
			(layer "F.SilkS")
		)
		(fp_line
			(start 0.7874 0.4064)
			(end -0.7874 0.4064)
			(stroke
				(width 0.1524)
				(type default)
			)
			(layer "F.SilkS")
		)
		(fp_line
			(start -0.7874 0.4064)
			(end -0.7874 -0.4064)
			(stroke
				(width 0.1524)
				(type default)
			)
			(layer "F.SilkS")
		)
		(fp_line
			(start -0.12065 -0.305054)
			(end -0.12065 -0.2794)
			(stroke
				(width 0.1)
				(type default)
			)
			(layer "F.Fab")
		)
		(fp_line
			(start -0.67945 -0.305054)
			(end -0.12065 -0.305054)
			(stroke
				(width 0.1)
				(type default)
			)
			(layer "F.Fab")
		)
		(fp_line
			(start 0.67945 -0.3048)
			(end 0.67945 0.3048)
			(stroke
				(width 0.1)
				(type default)
			)
			(layer "F.Fab")
		)
		(fp_line
			(start 0.12065 -0.3048)
			(end 0.67945 -0.3048)
			(stroke
				(width 0.1)
				(type default)
			)
			(layer "F.Fab")
		)
		(fp_line
			(start 0.12065 -0.2794)
			(end 0.12065 -0.3048)
			(stroke
				(width 0.1)
				(type default)
			)
			(layer "F.Fab")
		)
		(fp_line
			(start -0.12065 -0.2794)
			(end 0.12065 -0.2794)
			(stroke
				(width 0.1)
				(type default)
			)
			(layer "F.Fab")
		)
		(fp_line
			(start 0.120396 0.2794)
			(end -0.12065 0.2794)
			(stroke
				(width 0.1)
				(type default)
			)
			(layer "F.Fab")
		)
		(fp_line
			(start -0.12065 0.2794)
			(end -0.12065 0.3048)
			(stroke
				(width 0.1)
				(type default)
			)
			(layer "F.Fab")
		)
		(fp_line
			(start 0.67945 0.3048)
			(end 0.120396 0.3048)
			(stroke
				(width 0.1)
				(type default)
			)
			(layer "F.Fab")
		)
		(fp_line
			(start 0.120396 0.3048)
			(end 0.120396 0.2794)
			(stroke
				(width 0.1)
				(type default)
			)
			(layer "F.Fab")
		)
		(fp_line
			(start -0.12065 0.3048)
			(end -0.67945 0.3048)
			(stroke
				(width 0.1)
				(type default)
			)
			(layer "F.Fab")
		)
		(fp_line
			(start -0.67945 0.3048)
			(end -0.67945 -0.305054)
			(stroke
				(width 0.1)
				(type default)
			)
			(layer "F.Fab")
		)
		(pad "1" smd circle
			(at -0.40005 0 90)
			(size 0 0)
			(layers "F.Cu" "F.Mask" "F.Paste")
			(net "PVDDCR_CPU0_P1_PVCC")
		)
		(pad "2" smd circle
			(at 0.40005 0 90)
			(size 0 0)
			(layers "F.Cu" "F.Mask" "F.Paste")
			(net "GND")
		)
	)
	(footprint ""
		(layer "F.Cu")
		(at 90.68181 -182.675784 180)
		(property "Reference" "PU26"
			(at -0.51816 -6.641338 0)
			(unlocked yes)
			(layer "F.SilkS")
			(effects
				(font
					(size 0.7874 0.5842)
					(thickness 0.1524)
				)
				(justify left)
			)
		)
		(property "Value" ""
			(at 0 0 180)
			(layer "F.Fab")
			(effects
				(font
					(size 1.27 1.27)
				)
			)
		)
		(duplicate_pad_numbers_are_jumpers no)
		(fp_line
			(start 2.500122 2.999994)
			(end 2.2987 2.999994)
			(stroke
				(width 0.1524)
				(type default)
			)
			(layer "F.SilkS")
		)
		(fp_line
			(start 2.500122 2.339594)
			(end 2.500122 2.999994)
			(stroke
				(width 0.1524)
				(type default)
			)
			(layer "F.SilkS")
		)
		(fp_line
			(start 2.500122 -2.999994)
			(end 2.500122 -2.44348)
			(stroke
				(width 0.1524)
				(type default)
			)
			(layer "F.SilkS")
		)
		(fp_line
			(start 2.31394 -2.999994)
			(end 2.500122 -2.999994)
			(stroke
				(width 0.1524)
				(type default)
			)
			(layer "F.SilkS")
		)
		(fp_line
			(start -2.2987 2.999994)
			(end -2.500122 2.999994)
			(stroke
				(width 0.1524)
				(type default)
			)
			(layer "F.SilkS")
		)
		(fp_line
			(start -2.500122 2.999994)
			(end -2.500122 2.339594)
			(stroke
				(width 0.1524)
				(type default)
			)
			(layer "F.SilkS")
		)
		(fp_line
			(start -2.500122 0.6604)
			(end -2.500122 0.229108)
			(stroke
				(width 0.1524)
				(type default)
			)
			(layer "F.SilkS")
		)
		(fp_line
			(start -2.500122 -2.529078)
			(end -2.500122 -2.999994)
			(stroke
				(width 0.1524)
				(type default)
			)
			(layer "F.SilkS")
		)
		(fp_line
			(start -2.500122 -2.999994)
			(end -2.24409 -2.999994)
			(stroke
				(width 0.1524)
				(type default)
			)
			(layer "F.SilkS")
		)
		(fp_poly
			(pts
				(xy -2.708148 -2.422144) (xy -3.381756 -2.64668) (xy -2.932684 -3.095752)
			)
			(stroke
				(width 0)
				(type default)
			)
			(fill yes)
			(layer "F.SilkS")
		)
		(fp_line
			(start 2.500122 2.999994)
			(end -2.500122 2.999994)
			(stroke
				(width 0.1)
				(type default)
			)
			(layer "F.Fab")
		)
		(fp_line
			(start 2.500122 -2.999994)
			(end 2.500122 2.999994)
			(stroke
				(width 0.1)
				(type default)
			)
			(layer "F.Fab")
		)
		(fp_line
			(start -2.500122 2.999994)
			(end -2.500122 -2.999994)
			(stroke
				(width 0.1)
				(type default)
			)
			(layer "F.Fab")
		)
		(fp_line
			(start -2.500122 -2.999994)
			(end 2.500122 -2.999994)
			(stroke
				(width 0.1)
				(type default)
			)
			(layer "F.Fab")
		)
		(fp_poly
			(pts
				(xy -4.218432 -2.783078) (xy -4.218432 -1.767078) (xy -3.202432 -2.275078)
			)
			(stroke
				(width 0)
				(type default)
			)
			(fill yes)
			(layer "F.Fab")
		)
		(pad "1" smd rect
			(at -2.400046 -2.275078 270)
			(size 0.2286 0.6096)
			(layers "F.Cu" "F.Mask" "F.Paste")
			(net "PVDDCR_CPU0_P1_VOS2")
		)
		(pad "2" smd rect
			(at -2.400046 -1.82499 270)
			(size 0.2286 0.6096)
			(layers "F.Cu" "F.Mask" "F.Paste")
			(net "GND")
		)
		(pad "3" smd rect
			(at -2.400046 -1.374902 270)
			(size 0.2286 0.6096)
			(layers "F.Cu" "F.Mask" "F.Paste")
			(net "PVDDCR_CPU0_P1_VCC2")
		)
		(pad "4" smd rect
			(at -2.400046 -0.925068 270)
			(size 0.2286 0.6096)
			(layers "F.Cu" "F.Mask" "F.Paste")
			(net "PVDDCR_CPU0_P1_PVCC")
		)
		(pad "5" smd rect
			(at -2.400046 -0.47498 270)
			(size 0.2286 0.6096)
			(layers "F.Cu" "F.Mask" "F.Paste")
			(net "GND")
		)
		(pad "6" smd rect
			(at -2.400046 -0.024892 270)
			(size 0.2286 0.6096)
			(layers "F.Cu" "F.Mask" "F.Paste")
			(net "NC_PVDDCR_CPU0_P1_GL1_2")
		)
		(pad "7_9-20_24" smd circle
			(at 0 1.150112 270)
			(size 0 0)
			(layers "F.Cu" "F.Mask" "F.Paste")
			(net "GND")
		)
		(pad "10_19" smd rect
			(at 0 2.899918 270)
			(size 0.6096 4.318)
			(layers "F.Cu" "F.Mask" "F.Paste")
			(net "SW_PVDDCR_CPU0_P1_SW2")
		)
		(pad "25_29" smd rect
			(at 1.549908 -1.279906 90)
			(size 2.0574 2.3114)
			(layers "F.Cu" "F.Mask" "F.Paste")
			(net "SW_P12V_AUX_PVDDCR_CPU0_P1_FLT")
		)
		(pad "30" smd rect
			(at 2.05994 -2.899918 180)
			(size 0.2286 0.6096)
			(layers "F.Cu" "F.Mask" "F.Paste")
			(net "SW_P12V_AUX_PVDDCR_CPU0_P1_FLT")
		)
		(pad "31" smd rect
			(at 1.610106 -2.899918 180)
			(size 0.2286 0.6096)
			(layers "F.Cu" "F.Mask" "F.Paste")
			(net "NC_PVDDCR_CPU0_P1_DNC2")
		)
		(pad "32" smd rect
			(at 1.160018 -2.899918 180)
			(size 0.2286 0.6096)
			(layers "F.Cu" "F.Mask" "F.Paste")
			(net "SW_PVDDCR_CPU0_P1_PH2")
		)
		(pad "33" smd rect
			(at 0.70993 -2.899918 180)
			(size 0.2286 0.6096)
			(layers "F.Cu" "F.Mask" "F.Paste")
			(net "SW_PVDDCR_CPU0_P1_BOOT2")
		)
		(pad "34" smd rect
			(at 0.260096 -2.899918 180)
			(size 0.2286 0.6096)
			(layers "F.Cu" "F.Mask" "F.Paste")
			(net "PVDDCR_CPU0_P1_PWM2")
		)
		(pad "35" smd rect
			(at -0.189992 -2.899918 180)
			(size 0.2286 0.6096)
			(layers "F.Cu" "F.Mask" "F.Paste")
			(net "PVDDCR_CPU0_P1_VCC2")
		)
		(pad "36" smd rect
			(at -0.64008 -2.899918 180)
			(size 0.2286 0.6096)
			(layers "F.Cu" "F.Mask" "F.Paste")
			(net "PVDDCR_CPU0_P1_TEMP0")
		)
		(pad "37" smd rect
			(at -1.089914 -2.899918 180)
			(size 0.2286 0.6096)
			(layers "F.Cu" "F.Mask" "F.Paste")
			(net "PVDDCR_CPU0_P1_LSET2")
		)
		(pad "38" smd rect
			(at -1.540002 -2.899918 180)
			(size 0.2286 0.6096)
			(layers "F.Cu" "F.Mask" "F.Paste")
			(net "PVDDCR_CPU0_P1_IMON2")
		)
		(pad "39" smd rect
			(at -1.99009 -2.899918 180)
			(size 0.2286 0.6096)
			(layers "F.Cu" "F.Mask" "F.Paste")
			(net "PVDDCR_CPU0_P1_VCCS")
		)
		(pad "40" smd rect
			(at -0.87503 -1.27508 180)
			(size 1.7526 1.9558)
			(layers "F.Cu" "F.Mask" "F.Paste")
			(net "GND")
		)
		(pad "41" smd rect
			(at -1.525016 0.249936 90)
			(size 0.3048 0.4572)
			(layers "F.Cu" "F.Mask" "F.Paste")
			(net "NC_PVDDCR_CPU0_P1_GL2_2")
		)
		(zone
			(layer "F.Cu")
			(hatch none 0.5)
			(connect_pads
				(clearance 0)
			)
			(min_thickness 0.25)
			(keepout
				(tracks not_allowed)
				(vias allowed)
				(pads allowed)
				(copperpour not_allowed)
				(footprints allowed)
			)
			(placement
				(enabled no)
				(sheetname "")
			)
			(fill
				(thermal_gap 0.5)
				(thermal_bridge_width 0.5)
				(island_removal_mode 0)
			)
			(polygon
				(pts
					(xy 93.181932 -185.220102) (xy 93.181932 -184.926478) (xy 88.181688 -184.926478) (xy 88.181688 -185.220102)
					(xy 88.47201 -185.220102) (xy 92.89161 -185.220102)
				)
			)
		)
		(zone
			(layer "F.Cu")
			(hatch none 0.5)
			(connect_pads
				(clearance 0)
			)
			(min_thickness 0.25)
			(keepout
				(tracks not_allowed)
				(vias allowed)
				(pads allowed)
				(copperpour not_allowed)
				(footprints allowed)
			)
			(placement
				(enabled no)
				(sheetname "")
			)
			(fill
				(thermal_gap 0.5)
				(thermal_bridge_width 0.5)
				(island_removal_mode 0)
			)
			(polygon
				(pts
					(xy 90.62974 -182.429404) (xy 90.62974 -180.372004) (xy 92.48394 -180.372004) (xy 92.48394 -180.61305)
					(xy 92.726256 -180.61305) (xy 92.726256 -180.131466) (xy 88.825578 -180.131466) (xy 88.825578 -180.316378)
					(xy 90.338402 -180.316378) (xy 90.338402 -182.475378) (xy 88.181688 -182.475378) (xy 88.181688 -182.72506)
					(xy 90.334084 -182.72506)
				)
			)
		)
	)
	(footprint ""
		(layer "F.Cu")
		(at 187.127642 -413.64408 90)
		(property "Reference" "R9011"
			(at 0 0 90)
			(layer "F.SilkS")
			(hide yes)
			(effects
				(font
					(size 1.27 1.27)
				)
			)
		)
		(property "Value" ""
			(at 0 0 90)
			(layer "F.Fab")
			(effects
				(font
					(size 1.27 1.27)
				)
			)
		)
		(duplicate_pad_numbers_are_jumpers no)
		(fp_line
			(start 0.7874 -0.4064)
			(end 0.7874 0.4064)
			(stroke
				(width 0.1524)
				(type default)
			)
			(layer "F.SilkS")
		)
		(fp_line
			(start -0.7874 -0.4064)
			(end 0.7874 -0.4064)
			(stroke
				(width 0.1524)
				(type default)
			)
			(layer "F.SilkS")
		)
		(fp_line
			(start 0.7874 0.4064)
			(end -0.7874 0.4064)
			(stroke
				(width 0.1524)
				(type default)
			)
			(layer "F.SilkS")
		)
		(fp_line
			(start -0.7874 0.4064)
			(end -0.7874 -0.4064)
			(stroke
				(width 0.1524)
				(type default)
			)
			(layer "F.SilkS")
		)
		(fp_line
			(start -0.12065 -0.305054)
			(end -0.12065 -0.2794)
			(stroke
				(width 0.1)
				(type default)
			)
			(layer "F.Fab")
		)
		(fp_line
			(start -0.67945 -0.305054)
			(end -0.12065 -0.305054)
			(stroke
				(width 0.1)
				(type default)
			)
			(layer "F.Fab")
		)
		(fp_line
			(start 0.67945 -0.3048)
			(end 0.67945 0.3048)
			(stroke
				(width 0.1)
				(type default)
			)
			(layer "F.Fab")
		)
		(fp_line
			(start 0.12065 -0.3048)
			(end 0.67945 -0.3048)
			(stroke
				(width 0.1)
				(type default)
			)
			(layer "F.Fab")
		)
		(fp_line
			(start 0.12065 -0.2794)
			(end 0.12065 -0.3048)
			(stroke
				(width 0.1)
				(type default)
			)
			(layer "F.Fab")
		)
		(fp_line
			(start -0.12065 -0.2794)
			(end 0.12065 -0.2794)
			(stroke
				(width 0.1)
				(type default)
			)
			(layer "F.Fab")
		)
		(fp_line
			(start 0.120396 0.2794)
			(end -0.12065 0.2794)
			(stroke
				(width 0.1)
				(type default)
			)
			(layer "F.Fab")
		)
		(fp_line
			(start -0.12065 0.2794)
			(end -0.12065 0.3048)
			(stroke
				(width 0.1)
				(type default)
			)
			(layer "F.Fab")
		)
		(fp_line
			(start 0.67945 0.3048)
			(end 0.120396 0.3048)
			(stroke
				(width 0.1)
				(type default)
			)
			(layer "F.Fab")
		)
		(fp_line
			(start 0.120396 0.3048)
			(end 0.120396 0.2794)
			(stroke
				(width 0.1)
				(type default)
			)
			(layer "F.Fab")
		)
		(fp_line
			(start -0.12065 0.3048)
			(end -0.67945 0.3048)
			(stroke
				(width 0.1)
				(type default)
			)
			(layer "F.Fab")
		)
		(fp_line
			(start -0.67945 0.3048)
			(end -0.67945 -0.305054)
			(stroke
				(width 0.1)
				(type default)
			)
			(layer "F.Fab")
		)
		(pad "1" smd circle
			(at -0.40005 0 90)
			(size 0 0)
			(layers "F.Cu" "F.Mask" "F.Paste")
			(net "PRSNT_CABLE_GPU_B3_ISO_N")
		)
		(pad "2" smd circle
			(at 0.40005 0 90)
			(size 0 0)
			(layers "F.Cu" "F.Mask" "F.Paste")
			(net "PRSNT_CABLE_GPU_B3_ISO_R1_N")
		)
	)
)
